# BARRELEYE-G2-EXPANDER-EVT-HW-EBOM-X00-20161124-add_2nd_source_X06-20161207-Final.xls — TLA (bom)
| FOXCONN TECHNOLOGY GROUP |  |  |  |  |  |  |  |  |  |
| BILL OF MATERIAL |  |  |  |  |  |  |  |  |  |
| AA P/N | 1A42G4W00-600-G | CUSTOMER | <name> | Customer P/N |  | Product Code |  |  |  |
| PWA P/N |  | PWA DESCRIPTION | 磁碟陣列擴展板,ASSY,SAS EXPANDER BOARD,G,BARRELEYE G2 |  |  | PWA REV | X00 | Prepared By SE |  |
| Item | FOXCONN P/N | Customer P/N | Part Description | Manufacturer  Full Name | Manufacturer  Part Number | Qty | RoHS Status | Location | Remark |
| 1 | 7J-004-938 |  | L6 LABEL ( 12.7*11.1mm) | FOXCONN / EPD1 | 7J-004-938 | 1 | G |  |  |
| 2 | 48011V500-600-G |  | Heatsink,AL6063-T5,G,PHCM79X02012 | FOXCONN / T1 | PHCM79X02012 | 1 | G |  | Rev.X00 |
